FILE_TYPE = CONNECTIVITY;
{Allegro Design Entry HDL 17.2-2016 S081 (4005846) 1/11/2022}
"PAGE_NUMBER" = 167;
0"NC";
1"P5E_CPU1_PE2_TX_DN<7:0>";
2"P5E_CPU1_PE2_TX_DP<7:0>";
3"P5E_CPU1_PE2_TX_DN<15:8>";
4"P5E_CPU1_PE2_TX_DP<15:8>";
5"P5E_CPU1_PE2_TX_C_DN<7:0>";
6"P5E_CPU1_PE2_TX_C_DP<7:0>";
7"P5E_CPU1_PE2_TX_C_DN<15:8>";
8"P5E_CPU1_PE2_TX_C_DP<15:8>";
9"P5E_CPU1_PE0_TX_DN<7:0>";
10"P5E_CPU1_PE0_TX_DP<7:0>";
11"P5E_CPU1_PE0_TX_C_DP<7:0>";
12"P5E_CPU1_PE0_TX_C_DN<7:0>";
13"P5E_CPU1_PE0_TX_DN<15:8>";
14"P5E_CPU1_PE0_TX_DP<15:8>";
15"P5E_CPU1_PE0_TX_C_DP<15:8>";
16"P5E_CPU1_PE0_TX_C_DN<15:8>";
17"P5E_CPU1_PE0_TX_DP<15>";
18"P5E_CPU1_PE0_TX_DN<14>";
19"P5E_CPU1_PE0_TX_DP<14>";
20"P5E_CPU1_PE0_TX_DP<13>";
21"P5E_CPU1_PE0_TX_DN<12>";
22"P5E_CPU1_PE0_TX_DP<12>";
23"P5E_CPU1_PE0_TX_DP<11>";
24"P5E_CPU1_PE0_TX_DN<9>";
25"P5E_CPU1_PE0_TX_DP<7>";
26"P5E_CPU1_PE0_TX_DP<8>";
27"P5E_CPU1_PE0_TX_C_DP<7>";
28"P5E_CPU1_PE0_TX_C_DN<6>";
29"P5E_CPU1_PE0_TX_C_DP<6>";
30"P5E_CPU1_PE0_TX_C_DP<5>";
31"P5E_CPU1_PE0_TX_C_DP<4>";
32"P5E_CPU1_PE0_TX_C_DP<13>";
33"P5E_CPU1_PE0_TX_C_DP<15>";
34"P5E_CPU1_PE0_TX_C_DP<14>";
35"P5E_CPU1_PE0_TX_C_DN<15>";
36"P5E_CPU1_PE0_TX_C_DN<13>";
37"P5E_CPU1_PE0_TX_C_DN<14>";
38"P5E_CPU1_PE0_TX_C_DP<8>";
39"P5E_CPU1_PE0_TX_C_DP<10>";
40"P5E_CPU1_PE0_TX_C_DP<9>";
41"P5E_CPU1_PE0_TX_C_DP<11>";
42"P5E_CPU1_PE0_TX_C_DN<9>";
43"P5E_CPU1_PE0_TX_C_DN<12>";
44"P5E_CPU1_PE0_TX_C_DN<10>";
45"P5E_CPU1_PE0_TX_C_DN<8>";
46"P5E_CPU1_PE0_TX_C_DN<11>";
47"P5E_CPU1_PE0_TX_C_DP<12>";
48"P5E_CPU1_PE0_TX_DN<13>";
49"P5E_CPU1_PE0_TX_DN<15>";
50"P5E_CPU1_PE0_TX_DN<8>";
51"P5E_CPU1_PE0_TX_DP<10>";
52"P5E_CPU1_PE0_TX_DP<9>";
53"P5E_CPU1_PE0_TX_DN<11>";
54"P5E_CPU1_PE0_TX_DN<10>";
55"P5E_CPU1_PE0_TX_C_DN<5>";
56"P5E_CPU1_PE0_TX_C_DN<7>";
57"P5E_CPU1_PE0_TX_C_DN<4>";
58"P5E_CPU1_PE0_TX_C_DP<3>";
59"P5E_CPU1_PE0_TX_C_DP<1>";
60"P5E_CPU1_PE0_TX_C_DN<3>";
61"P5E_CPU1_PE0_TX_C_DN<0>";
62"P5E_CPU1_PE0_TX_C_DN<1>";
63"P5E_CPU1_PE0_TX_C_DN<2>";
64"P5E_CPU1_PE0_TX_C_DP<2>";
65"P5E_CPU1_PE0_TX_C_DP<0>";
66"P5E_CPU1_PE0_TX_DN<6>";
67"P5E_CPU1_PE0_TX_DN<4>";
68"P5E_CPU1_PE0_TX_DN<0>";
69"P5E_CPU1_PE0_TX_DN<3>";
70"P5E_CPU1_PE0_TX_DP<6>";
71"P5E_CPU1_PE0_TX_DP<5>";
72"P5E_CPU1_PE0_TX_DN<5>";
73"P5E_CPU1_PE0_TX_DP<1>";
74"P5E_CPU1_PE0_TX_DN<7>";
75"P5E_CPU1_PE0_TX_DN<1>";
76"P5E_CPU1_PE0_TX_DP<2>";
77"P5E_CPU1_PE0_TX_DP<3>";
78"P5E_CPU1_PE0_TX_DP<4>";
79"P5E_CPU1_PE0_TX_DP<0>";
80"P5E_CPU1_PE0_TX_DN<2>";
81"P5E_CPU1_PE2_TX_DP<14>";
82"P5E_CPU1_PE2_TX_C_DN<13>";
83"P5E_CPU1_PE2_TX_C_DP<6>";
84"P5E_CPU1_PE2_TX_DP<7>";
85"P5E_CPU1_PE2_TX_DP<11>";
86"P5E_CPU1_PE2_TX_DN<12>";
87"P5E_CPU1_PE2_TX_C_DN<12>";
88"P5E_CPU1_PE2_TX_C_DP<12>";
89"P5E_CPU1_PE2_TX_DP<12>";
90"P5E_CPU1_PE2_TX_DP<3>";
91"P5E_CPU1_PE2_TX_C_DN<2>";
92"P5E_CPU1_PE2_TX_C_DP<9>";
93"P5E_CPU1_PE2_TX_DP<9>";
94"P5E_CPU1_PE2_TX_C_DP<10>";
95"P5E_CPU1_PE2_TX_C_DN<1>";
96"P5E_CPU1_PE2_TX_DP<4>";
97"P5E_CPU1_PE2_TX_DN<4>";
98"P5E_CPU1_PE2_TX_DP<10>";
99"P5E_CPU1_PE2_TX_DP<6>";
100"P5E_CPU1_PE2_TX_DN<6>";
101"P5E_CPU1_PE2_TX_C_DP<11>";
102"P5E_CPU1_PE2_TX_C_DN<0>";
103"P5E_CPU1_PE2_TX_C_DP<1>";
104"P5E_CPU1_PE2_TX_C_DP<13>";
105"P5E_CPU1_PE2_TX_C_DP<14>";
106"P5E_CPU1_PE2_TX_C_DP<15>";
107"P5E_CPU1_PE2_TX_C_DN<15>";
108"P5E_CPU1_PE2_TX_C_DN<14>";
109"P5E_CPU1_PE2_TX_C_DP<8>";
110"P5E_CPU1_PE2_TX_C_DN<11>";
111"P5E_CPU1_PE2_TX_C_DN<10>";
112"P5E_CPU1_PE2_TX_C_DN<8>";
113"P5E_CPU1_PE2_TX_C_DN<9>";
114"P5E_CPU1_PE2_TX_C_DP<7>";
115"P5E_CPU1_PE2_TX_C_DP<5>";
116"P5E_CPU1_PE2_TX_C_DN<7>";
117"P5E_CPU1_PE2_TX_C_DN<6>";
118"P5E_CPU1_PE2_TX_C_DN<5>";
119"P5E_CPU1_PE2_TX_C_DN<4>";
120"P5E_CPU1_PE2_TX_C_DP<0>";
121"P5E_CPU1_PE2_TX_C_DP<3>";
122"P5E_CPU1_PE2_TX_C_DP<2>";
123"P5E_CPU1_PE2_TX_C_DP<4>";
124"P5E_CPU1_PE2_TX_C_DN<3>";
125"P5E_CPU1_PE2_TX_DP<15>";
126"P5E_CPU1_PE2_TX_DP<13>";
127"P5E_CPU1_PE2_TX_DP<8>";
128"P5E_CPU1_PE2_TX_DN<8>";
129"P5E_CPU1_PE2_TX_DN<11>";
130"P5E_CPU1_PE2_TX_DN<9>";
131"P5E_CPU1_PE2_TX_DN<10>";
132"P5E_CPU1_PE2_TX_DN<14>";
133"P5E_CPU1_PE2_TX_DN<13>";
134"P5E_CPU1_PE2_TX_DN<15>";
135"P5E_CPU1_PE2_TX_DP<5>";
136"P5E_CPU1_PE2_TX_DP<0>";
137"P5E_CPU1_PE2_TX_DP<2>";
138"P5E_CPU1_PE2_TX_DP<1>";
139"P5E_CPU1_PE2_TX_DN<0>";
140"P5E_CPU1_PE2_TX_DN<3>";
141"P5E_CPU1_PE2_TX_DN<1>";
142"P5E_CPU1_PE2_TX_DN<2>";
143"P5E_CPU1_PE2_TX_DN<7>";
144"P5E_CPU1_PE2_TX_DN<5>";
%"TAP"
"1","(2650,200)","2","standard","I109";
;
CDS_LIB"standard"
BODY_TYPE"PLUMBING"
HDL_TAP"TRUE";
"B \NAC \NWC"2;
"S \NAC"
BN"0"136;
%"TAP"
"1","(2650,400)","2","standard","I110";
;
CDS_LIB"standard"
BODY_TYPE"PLUMBING"
HDL_TAP"TRUE";
"B \NAC \NWC"2;
"S \NAC"
BN"1"138;
%"TAP"
"1","(2650,600)","2","standard","I111";
;
CDS_LIB"standard"
BODY_TYPE"PLUMBING"
HDL_TAP"TRUE";
"B \NAC \NWC"2;
"S \NAC"
BN"2"137;
%"TAP"
"1","(2650,800)","2","standard","I112";
;
CDS_LIB"standard"
BODY_TYPE"PLUMBING"
HDL_TAP"TRUE";
"B \NAC \NWC"2;
"S \NAC"
BN"3"90;
%"TAP"
"1","(2650,1000)","2","standard","I113";
;
CDS_LIB"standard"
BODY_TYPE"PLUMBING"
HDL_TAP"TRUE";
"B \NAC \NWC"2;
"S \NAC"
BN"4"96;
%"TAP"
"1","(2650,1200)","2","standard","I114";
;
CDS_LIB"standard"
BODY_TYPE"PLUMBING"
HDL_TAP"TRUE";
"B \NAC \NWC"2;
"S \NAC"
BN"5"135;
%"TAP"
"1","(2650,1400)","2","standard","I115";
;
CDS_LIB"standard"
BODY_TYPE"PLUMBING"
HDL_TAP"TRUE";
"B \NAC \NWC"2;
"S \NAC"
BN"6"99;
%"TAP"
"1","(2650,1600)","2","standard","I116";
;
CDS_LIB"standard"
BODY_TYPE"PLUMBING"
HDL_TAP"TRUE";
"B \NAC \NWC"2;
"S \NAC"
BN"7"84;
%"TAP"
"1","(2900,250)","2","standard","I117";
;
CDS_LIB"standard"
BODY_TYPE"PLUMBING"
HDL_TAP"TRUE";
"B \NAC \NWC"1;
"S \NAC"
BN"0"139;
%"TAP"
"1","(2900,450)","2","standard","I118";
;
CDS_LIB"standard"
BODY_TYPE"PLUMBING"
HDL_TAP"TRUE";
"B \NAC \NWC"1;
"S \NAC"
BN"1"141;
%"TAP"
"1","(2900,650)","2","standard","I119";
;
CDS_LIB"standard"
BODY_TYPE"PLUMBING"
HDL_TAP"TRUE";
"B \NAC \NWC"1;
"S \NAC"
BN"2"142;
%"TAP"
"1","(2900,850)","2","standard","I120";
;
CDS_LIB"standard"
BODY_TYPE"PLUMBING"
HDL_TAP"TRUE";
"B \NAC \NWC"1;
"S \NAC"
BN"3"140;
%"TAP"
"1","(2900,1050)","2","standard","I121";
;
CDS_LIB"standard"
BODY_TYPE"PLUMBING"
HDL_TAP"TRUE";
"B \NAC \NWC"1;
"S \NAC"
BN"4"97;
%"Q_CAP_DIFFBUS"
"2","(3625,200)","2","pure_quanta","I122";
;
PART_NUMBER"SP_CH4221MEE01"
VALUE"DIFF BUS_0.22UF"
$LOCATION"C773"
PIN_NAMES_ROTATE"TRUE"
CDS_LIB"pure_quanta"
CDS_LMAN_SYM_OUTLINE"-25,50,25,-50"
VOLTAGE"6.3V"
MATERIAL"X6S"
PACK_TYPE"C0201"
TOLERANCE"20%"
$LOCATION"C773"
CDS_LOCATION"C773"
$SEC"1"
CDS_SEC"1";
"2"
$PN"2"136;
"1"
$PN"1"120;
%"Q_CAP_DIFFBUS"
"2","(3625,250)","2","pure_quanta","I123";
;
PART_NUMBER"SP_CH4221MEE01"
VALUE"DIFF BUS_0.22UF"
$LOCATION"C772"
PIN_NAMES_ROTATE"TRUE"
CDS_LIB"pure_quanta"
CDS_LMAN_SYM_OUTLINE"-25,50,25,-50"
VOLTAGE"6.3V"
MATERIAL"X6S"
PACK_TYPE"C0201"
TOLERANCE"20%"
$LOCATION"C772"
CDS_LOCATION"C772"
$SEC"1"
CDS_SEC"1";
"2"
$PN"2"139;
"1"
$PN"1"102;
%"Q_CAP_DIFFBUS"
"2","(3625,400)","2","pure_quanta","I124";
;
PART_NUMBER"SP_CH4221MEE01"
VALUE"DIFF BUS_0.22UF"
$LOCATION"C771"
PIN_NAMES_ROTATE"TRUE"
CDS_LIB"pure_quanta"
CDS_LMAN_SYM_OUTLINE"-25,50,25,-50"
VOLTAGE"6.3V"
MATERIAL"X6S"
PACK_TYPE"C0201"
TOLERANCE"20%"
$LOCATION"C771"
CDS_LOCATION"C771"
$SEC"1"
CDS_SEC"1";
"2"
$PN"2"138;
"1"
$PN"1"103;
%"Q_CAP_DIFFBUS"
"2","(3625,450)","2","pure_quanta","I125";
;
PART_NUMBER"SP_CH4221MEE01"
VALUE"DIFF BUS_0.22UF"
$LOCATION"C770"
PIN_NAMES_ROTATE"TRUE"
CDS_LMAN_SYM_OUTLINE"-25,50,25,-50"
CDS_LIB"pure_quanta"
VOLTAGE"6.3V"
MATERIAL"X6S"
PACK_TYPE"C0201"
TOLERANCE"20%"
$LOCATION"C770"
CDS_LOCATION"C770"
$SEC"1"
CDS_SEC"1";
"2"
$PN"2"141;
"1"
$PN"1"95;
%"Q_CAP_DIFFBUS"
"2","(3625,600)","2","pure_quanta","I126";
;
PART_NUMBER"SP_CH4221MEE01"
VALUE"DIFF BUS_0.22UF"
$LOCATION"C769"
PIN_NAMES_ROTATE"TRUE"
CDS_LIB"pure_quanta"
CDS_LMAN_SYM_OUTLINE"-25,50,25,-50"
VOLTAGE"6.3V"
MATERIAL"X6S"
PACK_TYPE"C0201"
TOLERANCE"20%"
$LOCATION"C769"
CDS_LOCATION"C769"
$SEC"1"
CDS_SEC"1";
"2"
$PN"2"137;
"1"
$PN"1"122;
%"Q_CAP_DIFFBUS"
"2","(3625,650)","2","pure_quanta","I127";
;
PART_NUMBER"SP_CH4221MEE01"
VALUE"DIFF BUS_0.22UF"
$LOCATION"C768"
PIN_NAMES_ROTATE"TRUE"
CDS_LIB"pure_quanta"
CDS_LMAN_SYM_OUTLINE"-25,50,25,-50"
VOLTAGE"6.3V"
MATERIAL"X6S"
PACK_TYPE"C0201"
TOLERANCE"20%"
$LOCATION"C768"
CDS_LOCATION"C768"
$SEC"1"
CDS_SEC"1";
"2"
$PN"2"142;
"1"
$PN"1"91;
%"Q_CAP_DIFFBUS"
"2","(3625,800)","2","pure_quanta","I128";
;
PART_NUMBER"SP_CH4221MEE01"
VALUE"DIFF BUS_0.22UF"
$LOCATION"C767"
PIN_NAMES_ROTATE"TRUE"
CDS_LMAN_SYM_OUTLINE"-25,50,25,-50"
CDS_LIB"pure_quanta"
VOLTAGE"6.3V"
MATERIAL"X6S"
PACK_TYPE"C0201"
TOLERANCE"20%"
$LOCATION"C767"
CDS_LOCATION"C767"
$SEC"1"
CDS_SEC"1";
"2"
$PN"2"90;
"1"
$PN"1"121;
%"Q_CAP_DIFFBUS"
"2","(3625,850)","2","pure_quanta","I129";
;
PART_NUMBER"SP_CH4221MEE01"
VALUE"DIFF BUS_0.22UF"
$LOCATION"C766"
PIN_NAMES_ROTATE"TRUE"
CDS_LMAN_SYM_OUTLINE"-25,50,25,-50"
CDS_LIB"pure_quanta"
VOLTAGE"6.3V"
MATERIAL"X6S"
PACK_TYPE"C0201"
TOLERANCE"20%"
$LOCATION"C766"
CDS_LOCATION"C766"
$SEC"1"
CDS_SEC"1";
"2"
$PN"2"140;
"1"
$PN"1"124;
%"Q_CAP_DIFFBUS"
"2","(3625,1050)","2","pure_quanta","I130";
;
PART_NUMBER"SP_CH4221MEE01"
VALUE"DIFF BUS_0.22UF"
$LOCATION"C764"
PIN_NAMES_ROTATE"TRUE"
CDS_LIB"pure_quanta"
CDS_LMAN_SYM_OUTLINE"-25,50,25,-50"
VOLTAGE"6.3V"
MATERIAL"X6S"
PACK_TYPE"C0201"
TOLERANCE"20%"
$LOCATION"C764"
CDS_LOCATION"C764"
$SEC"1"
CDS_SEC"1";
"2"
$PN"2"97;
"1"
$PN"1"119;
%"Q_CAP_DIFFBUS"
"2","(3625,1000)","2","pure_quanta","I131";
;
PART_NUMBER"SP_CH4221MEE01"
VALUE"DIFF BUS_0.22UF"
$LOCATION"C765"
PIN_NAMES_ROTATE"TRUE"
CDS_LIB"pure_quanta"
CDS_LMAN_SYM_OUTLINE"-25,50,25,-50"
VOLTAGE"6.3V"
MATERIAL"X6S"
PACK_TYPE"C0201"
TOLERANCE"20%"
$LOCATION"C765"
CDS_LOCATION"C765"
$SEC"1"
CDS_SEC"1";
"2"
$PN"2"96;
"1"
$PN"1"123;
%"TAP"
"1","(2900,1250)","2","standard","I132";
;
CDS_LIB"standard"
BODY_TYPE"PLUMBING"
HDL_TAP"TRUE";
"B \NAC \NWC"1;
"S \NAC"
BN"5"144;
%"TAP"
"1","(2900,1450)","2","standard","I133";
;
CDS_LIB"standard"
BODY_TYPE"PLUMBING"
HDL_TAP"TRUE";
"B \NAC \NWC"1;
"S \NAC"
BN"6"100;
%"TAP"
"1","(2900,1650)","2","standard","I134";
;
CDS_LIB"standard"
BODY_TYPE"PLUMBING"
HDL_TAP"TRUE";
"B \NAC \NWC"1;
"S \NAC"
BN"7"143;
%"Q_CAP_DIFFBUS"
"2","(3625,1200)","2","pure_quanta","I135";
;
PART_NUMBER"SP_CH4221MEE01"
VALUE"DIFF BUS_0.22UF"
$LOCATION"C763"
PIN_NAMES_ROTATE"TRUE"
CDS_LIB"pure_quanta"
CDS_LMAN_SYM_OUTLINE"-25,50,25,-50"
VOLTAGE"6.3V"
MATERIAL"X6S"
PACK_TYPE"C0201"
TOLERANCE"20%"
$LOCATION"C763"
CDS_LOCATION"C763"
$SEC"1"
CDS_SEC"1";
"2"
$PN"2"135;
"1"
$PN"1"115;
%"Q_CAP_DIFFBUS"
"2","(3625,1250)","2","pure_quanta","I136";
;
PART_NUMBER"SP_CH4221MEE01"
VALUE"DIFF BUS_0.22UF"
$LOCATION"C762"
PIN_NAMES_ROTATE"TRUE"
CDS_LIB"pure_quanta"
CDS_LMAN_SYM_OUTLINE"-25,50,25,-50"
VOLTAGE"6.3V"
MATERIAL"X6S"
PACK_TYPE"C0201"
TOLERANCE"20%"
$LOCATION"C762"
CDS_LOCATION"C762"
$SEC"1"
CDS_SEC"1";
"2"
$PN"2"144;
"1"
$PN"1"118;
%"Q_CAP_DIFFBUS"
"2","(3625,1400)","2","pure_quanta","I137";
;
PART_NUMBER"SP_CH4221MEE01"
VALUE"DIFF BUS_0.22UF"
$LOCATION"C761"
PIN_NAMES_ROTATE"TRUE"
CDS_LIB"pure_quanta"
CDS_LMAN_SYM_OUTLINE"-25,50,25,-50"
VOLTAGE"6.3V"
MATERIAL"X6S"
PACK_TYPE"C0201"
TOLERANCE"20%"
$LOCATION"C761"
CDS_LOCATION"C761"
$SEC"1"
CDS_SEC"1";
"2"
$PN"2"99;
"1"
$PN"1"83;
%"Q_CAP_DIFFBUS"
"2","(3625,1450)","2","pure_quanta","I138";
;
PART_NUMBER"SP_CH4221MEE01"
VALUE"DIFF BUS_0.22UF"
$LOCATION"C760"
PIN_NAMES_ROTATE"TRUE"
CDS_LIB"pure_quanta"
CDS_LMAN_SYM_OUTLINE"-25,50,25,-50"
VOLTAGE"6.3V"
MATERIAL"X6S"
PACK_TYPE"C0201"
TOLERANCE"20%"
$LOCATION"C760"
CDS_LOCATION"C760"
$SEC"1"
CDS_SEC"1";
"2"
$PN"2"100;
"1"
$PN"1"117;
%"Q_CAP_DIFFBUS"
"2","(3625,1600)","2","pure_quanta","I139";
;
PART_NUMBER"SP_CH4221MEE01"
VALUE"DIFF BUS_0.22UF"
$LOCATION"C759"
PIN_NAMES_ROTATE"TRUE"
CDS_LIB"pure_quanta"
CDS_LMAN_SYM_OUTLINE"-25,50,25,-50"
VOLTAGE"6.3V"
MATERIAL"X6S"
PACK_TYPE"C0201"
TOLERANCE"20%"
$LOCATION"C759"
CDS_LOCATION"C759"
$SEC"1"
CDS_SEC"1";
"2"
$PN"2"84;
"1"
$PN"1"114;
%"Q_CAP_DIFFBUS"
"2","(3625,1650)","2","pure_quanta","I140";
;
PART_NUMBER"SP_CH4221MEE01"
VALUE"DIFF BUS_0.22UF"
$LOCATION"C758"
PIN_NAMES_ROTATE"TRUE"
CDS_LMAN_SYM_OUTLINE"-25,50,25,-50"
CDS_LIB"pure_quanta"
VOLTAGE"6.3V"
MATERIAL"X6S"
PACK_TYPE"C0201"
TOLERANCE"20%"
$LOCATION"C758"
CDS_LOCATION"C758"
$SEC"1"
CDS_SEC"1";
"2"
$PN"2"143;
"1"
$PN"1"116;
%"TAP"
"1","(2650,2175)","2","standard","I141";
;
CDS_LIB"standard"
BODY_TYPE"PLUMBING"
HDL_TAP"TRUE";
"B \NAC \NWC"4;
"S \NAC"
BN"8"127;
%"TAP"
"1","(2650,2375)","2","standard","I142";
;
CDS_LIB"standard"
BODY_TYPE"PLUMBING"
HDL_TAP"TRUE";
"B \NAC \NWC"4;
"S \NAC"
BN"9"93;
%"TAP"
"1","(2650,2575)","2","standard","I143";
;
CDS_LIB"standard"
BODY_TYPE"PLUMBING"
HDL_TAP"TRUE";
"B \NAC \NWC"4;
"S \NAC"
BN"10"98;
%"TAP"
"1","(2650,2775)","2","standard","I144";
;
CDS_LIB"standard"
BODY_TYPE"PLUMBING"
HDL_TAP"TRUE";
"B \NAC \NWC"4;
"S \NAC"
BN"11"85;
%"TAP"
"1","(2650,2975)","2","standard","I145";
;
CDS_LIB"standard"
BODY_TYPE"PLUMBING"
HDL_TAP"TRUE";
"B \NAC \NWC"4;
"S \NAC"
BN"12"89;
%"TAP"
"1","(2650,3175)","2","standard","I146";
;
CDS_LIB"standard"
BODY_TYPE"PLUMBING"
HDL_TAP"TRUE";
"B \NAC \NWC"4;
"S \NAC"
BN"13"126;
%"TAP"
"1","(2650,3375)","2","standard","I147";
;
CDS_LIB"standard"
BODY_TYPE"PLUMBING"
HDL_TAP"TRUE";
"B \NAC \NWC"4;
"S \NAC"
BN"14"81;
%"TAP"
"1","(2650,3575)","2","standard","I148";
;
CDS_LIB"standard"
BODY_TYPE"PLUMBING"
HDL_TAP"TRUE";
"B \NAC \NWC"4;
"S \NAC"
BN"15"125;
%"TAP"
"1","(2900,2225)","2","standard","I149";
;
CDS_LIB"standard"
BODY_TYPE"PLUMBING"
HDL_TAP"TRUE";
"B \NAC \NWC"3;
"S \NAC"
BN"8"128;
%"TAP"
"1","(2900,2425)","2","standard","I150";
;
CDS_LIB"standard"
BODY_TYPE"PLUMBING"
HDL_TAP"TRUE";
"B \NAC \NWC"3;
"S \NAC"
BN"9"130;
%"TAP"
"1","(2900,2625)","2","standard","I151";
;
CDS_LIB"standard"
BODY_TYPE"PLUMBING"
HDL_TAP"TRUE";
"B \NAC \NWC"3;
"S \NAC"
BN"10"131;
%"TAP"
"1","(2900,2825)","2","standard","I152";
;
CDS_LIB"standard"
BODY_TYPE"PLUMBING"
HDL_TAP"TRUE";
"B \NAC \NWC"3;
"S \NAC"
BN"11"129;
%"TAP"
"1","(2900,3025)","2","standard","I153";
;
CDS_LIB"standard"
BODY_TYPE"PLUMBING"
HDL_TAP"TRUE";
"B \NAC \NWC"3;
"S \NAC"
BN"12"86;
%"Q_CAP_DIFFBUS"
"2","(3625,2225)","2","pure_quanta","I154";
;
PART_NUMBER"SP_CH4221MEE01"
VALUE"DIFF BUS_0.22UF"
$LOCATION"C756"
CDS_LMAN_SYM_OUTLINE"-25,50,25,-50"
CDS_LIB"pure_quanta"
PIN_NAMES_ROTATE"TRUE"
VOLTAGE"6.3V"
MATERIAL"X6S"
PACK_TYPE"C0201"
TOLERANCE"20%"
$LOCATION"C756"
CDS_LOCATION"C756"
$SEC"1"
CDS_SEC"1";
"2"
$PN"2"128;
"1"
$PN"1"112;
%"Q_CAP_DIFFBUS"
"2","(3625,2175)","2","pure_quanta","I155";
;
PART_NUMBER"SP_CH4221MEE01"
VALUE"DIFF BUS_0.22UF"
$LOCATION"C757"
CDS_LMAN_SYM_OUTLINE"-25,50,25,-50"
CDS_LIB"pure_quanta"
PIN_NAMES_ROTATE"TRUE"
VOLTAGE"6.3V"
MATERIAL"X6S"
PACK_TYPE"C0201"
TOLERANCE"20%"
$LOCATION"C757"
CDS_LOCATION"C757"
$SEC"1"
CDS_SEC"1";
"2"
$PN"2"127;
"1"
$PN"1"109;
%"Q_CAP_DIFFBUS"
"2","(3625,2375)","2","pure_quanta","I156";
;
PART_NUMBER"SP_CH4221MEE01"
VALUE"DIFF BUS_0.22UF"
$LOCATION"C755"
CDS_LMAN_SYM_OUTLINE"-25,50,25,-50"
CDS_LIB"pure_quanta"
PIN_NAMES_ROTATE"TRUE"
VOLTAGE"6.3V"
MATERIAL"X6S"
PACK_TYPE"C0201"
TOLERANCE"20%"
$LOCATION"C755"
CDS_LOCATION"C755"
$SEC"1"
CDS_SEC"1";
"2"
$PN"2"93;
"1"
$PN"1"92;
%"Q_CAP_DIFFBUS"
"2","(3625,2425)","2","pure_quanta","I157";
;
PART_NUMBER"SP_CH4221MEE01"
VALUE"DIFF BUS_0.22UF"
$LOCATION"C754"
CDS_LIB"pure_quanta"
CDS_LMAN_SYM_OUTLINE"-25,50,25,-50"
PIN_NAMES_ROTATE"TRUE"
VOLTAGE"6.3V"
MATERIAL"X6S"
PACK_TYPE"C0201"
TOLERANCE"20%"
$LOCATION"C754"
CDS_LOCATION"C754"
$SEC"1"
CDS_SEC"1";
"2"
$PN"2"130;
"1"
$PN"1"113;
%"Q_CAP_DIFFBUS"
"2","(3625,2575)","2","pure_quanta","I158";
;
PART_NUMBER"SP_CH4221MEE01"
VALUE"DIFF BUS_0.22UF"
$LOCATION"C753"
CDS_LMAN_SYM_OUTLINE"-25,50,25,-50"
CDS_LIB"pure_quanta"
PIN_NAMES_ROTATE"TRUE"
VOLTAGE"6.3V"
MATERIAL"X6S"
PACK_TYPE"C0201"
TOLERANCE"20%"
$LOCATION"C753"
CDS_LOCATION"C753"
$SEC"1"
CDS_SEC"1";
"2"
$PN"2"98;
"1"
$PN"1"94;
%"Q_CAP_DIFFBUS"
"2","(3625,2625)","2","pure_quanta","I159";
;
PART_NUMBER"SP_CH4221MEE01"
VALUE"DIFF BUS_0.22UF"
$LOCATION"C752"
CDS_LMAN_SYM_OUTLINE"-25,50,25,-50"
CDS_LIB"pure_quanta"
PIN_NAMES_ROTATE"TRUE"
VOLTAGE"6.3V"
MATERIAL"X6S"
PACK_TYPE"C0201"
TOLERANCE"20%"
$LOCATION"C752"
CDS_LOCATION"C752"
$SEC"1"
CDS_SEC"1";
"2"
$PN"2"131;
"1"
$PN"1"111;
%"Q_CAP_DIFFBUS"
"2","(3625,2825)","2","pure_quanta","I160";
;
PART_NUMBER"SP_CH4221MEE01"
VALUE"DIFF BUS_0.22UF"
$LOCATION"C750"
CDS_LIB"pure_quanta"
CDS_LMAN_SYM_OUTLINE"-25,50,25,-50"
PIN_NAMES_ROTATE"TRUE"
VOLTAGE"6.3V"
MATERIAL"X6S"
PACK_TYPE"C0201"
TOLERANCE"20%"
$LOCATION"C750"
CDS_LOCATION"C750"
$SEC"1"
CDS_SEC"1";
"2"
$PN"2"129;
"1"
$PN"1"110;
%"Q_CAP_DIFFBUS"
"2","(3625,2775)","2","pure_quanta","I161";
;
PART_NUMBER"SP_CH4221MEE01"
VALUE"DIFF BUS_0.22UF"
$LOCATION"C751"
CDS_LIB"pure_quanta"
CDS_LMAN_SYM_OUTLINE"-25,50,25,-50"
PIN_NAMES_ROTATE"TRUE"
VOLTAGE"6.3V"
MATERIAL"X6S"
PACK_TYPE"C0201"
TOLERANCE"20%"
$LOCATION"C751"
CDS_LOCATION"C751"
$SEC"1"
CDS_SEC"1";
"2"
$PN"2"85;
"1"
$PN"1"101;
%"Q_CAP_DIFFBUS"
"2","(3625,2975)","2","pure_quanta","I162";
;
PART_NUMBER"SP_CH4221MEE01"
VALUE"DIFF BUS_0.22UF"
$LOCATION"C749"
CDS_LMAN_SYM_OUTLINE"-25,50,25,-50"
CDS_LIB"pure_quanta"
PIN_NAMES_ROTATE"TRUE"
VOLTAGE"6.3V"
MATERIAL"X6S"
PACK_TYPE"C0201"
TOLERANCE"20%"
$LOCATION"C749"
CDS_LOCATION"C749"
$SEC"1"
CDS_SEC"1";
"2"
$PN"2"89;
"1"
$PN"1"88;
%"Q_CAP_DIFFBUS"
"2","(3625,3025)","2","pure_quanta","I163";
;
PART_NUMBER"SP_CH4221MEE01"
VALUE"DIFF BUS_0.22UF"
$LOCATION"C748"
CDS_LMAN_SYM_OUTLINE"-25,50,25,-50"
CDS_LIB"pure_quanta"
PIN_NAMES_ROTATE"TRUE"
VOLTAGE"6.3V"
MATERIAL"X6S"
PACK_TYPE"C0201"
TOLERANCE"20%"
$LOCATION"C748"
CDS_LOCATION"C748"
$SEC"1"
CDS_SEC"1";
"2"
$PN"2"86;
"1"
$PN"1"87;
%"TAP"
"1","(2900,3225)","2","standard","I164";
;
CDS_LIB"standard"
BODY_TYPE"PLUMBING"
HDL_TAP"TRUE";
"B \NAC \NWC"3;
"S \NAC"
BN"13"133;
%"TAP"
"1","(2900,3425)","2","standard","I165";
;
CDS_LIB"standard"
BODY_TYPE"PLUMBING"
HDL_TAP"TRUE";
"B \NAC \NWC"3;
"S \NAC"
BN"14"132;
%"TAP"
"1","(2900,3625)","2","standard","I166";
;
CDS_LIB"standard"
BODY_TYPE"PLUMBING"
HDL_TAP"TRUE";
"B \NAC \NWC"3;
"S \NAC"
BN"15"134;
%"Q_CAP_DIFFBUS"
"2","(3625,3175)","2","pure_quanta","I167";
;
PART_NUMBER"SP_CH4221MEE01"
VALUE"DIFF BUS_0.22UF"
$LOCATION"C747"
CDS_LMAN_SYM_OUTLINE"-25,50,25,-50"
CDS_LIB"pure_quanta"
PIN_NAMES_ROTATE"TRUE"
VOLTAGE"6.3V"
MATERIAL"X6S"
PACK_TYPE"C0201"
TOLERANCE"20%"
$LOCATION"C747"
CDS_LOCATION"C747"
$SEC"1"
CDS_SEC"1";
"2"
$PN"2"126;
"1"
$PN"1"104;
%"Q_CAP_DIFFBUS"
"2","(3625,3225)","2","pure_quanta","I168";
;
PART_NUMBER"SP_CH4221MEE01"
VALUE"DIFF BUS_0.22UF"
$LOCATION"C746"
CDS_LMAN_SYM_OUTLINE"-25,50,25,-50"
CDS_LIB"pure_quanta"
PIN_NAMES_ROTATE"TRUE"
VOLTAGE"6.3V"
MATERIAL"X6S"
PACK_TYPE"C0201"
TOLERANCE"20%"
$LOCATION"C746"
CDS_LOCATION"C746"
$SEC"1"
CDS_SEC"1";
"2"
$PN"2"133;
"1"
$PN"1"82;
%"Q_CAP_DIFFBUS"
"2","(3625,3375)","2","pure_quanta","I169";
;
PART_NUMBER"SP_CH4221MEE01"
VALUE"DIFF BUS_0.22UF"
$LOCATION"C745"
CDS_LMAN_SYM_OUTLINE"-25,50,25,-50"
CDS_LIB"pure_quanta"
PIN_NAMES_ROTATE"TRUE"
VOLTAGE"6.3V"
MATERIAL"X6S"
PACK_TYPE"C0201"
TOLERANCE"20%"
$LOCATION"C745"
CDS_LOCATION"C745"
$SEC"1"
CDS_SEC"1";
"2"
$PN"2"81;
"1"
$PN"1"105;
%"Q_CAP_DIFFBUS"
"2","(3625,3425)","2","pure_quanta","I170";
;
PART_NUMBER"SP_CH4221MEE01"
VALUE"DIFF BUS_0.22UF"
$LOCATION"C744"
CDS_LMAN_SYM_OUTLINE"-25,50,25,-50"
CDS_LIB"pure_quanta"
PIN_NAMES_ROTATE"TRUE"
VOLTAGE"6.3V"
MATERIAL"X6S"
PACK_TYPE"C0201"
TOLERANCE"20%"
$LOCATION"C744"
CDS_LOCATION"C744"
$SEC"1"
CDS_SEC"1";
"2"
$PN"2"132;
"1"
$PN"1"108;
%"Q_CAP_DIFFBUS"
"2","(3625,3575)","2","pure_quanta","I171";
;
PART_NUMBER"SP_CH4221MEE01"
VALUE"DIFF BUS_0.22UF"
$LOCATION"C743"
CDS_LMAN_SYM_OUTLINE"-25,50,25,-50"
CDS_LIB"pure_quanta"
PIN_NAMES_ROTATE"TRUE"
VOLTAGE"6.3V"
MATERIAL"X6S"
PACK_TYPE"C0201"
TOLERANCE"20%"
$LOCATION"C743"
CDS_LOCATION"C743"
$SEC"1"
CDS_SEC"1";
"2"
$PN"2"125;
"1"
$PN"1"106;
%"Q_CAP_DIFFBUS"
"2","(3625,3625)","2","pure_quanta","I172";
;
PART_NUMBER"SP_CH4221MEE01"
VOLTAGE"6.3V"
TOLERANCE"20%"
MATERIAL"X6S"
PACK_TYPE"C0201"
VALUE"DIFF BUS_0.22UF"
$LOCATION"C742"
CDS_LIB"pure_quanta"
CDS_LMAN_SYM_OUTLINE"-25,50,25,-50"
PIN_NAMES_ROTATE"TRUE"
$LOCATION"C742"
CDS_LOCATION"C742"
$SEC"1"
CDS_SEC"1";
"2"
$PN"2"134;
"1"
$PN"1"107;
%"TAP"
"1","(4175,250)","0","standard","I173";
;
CDS_LIB"standard"
BODY_TYPE"PLUMBING"
HDL_TAP"TRUE";
"B \NAC \NWC"5;
"S \NAC"
BN"0"102;
%"TAP"
"1","(4175,450)","0","standard","I174";
;
CDS_LIB"standard"
BODY_TYPE"PLUMBING"
HDL_TAP"TRUE";
"B \NAC \NWC"5;
"S \NAC"
BN"1"95;
%"TAP"
"1","(4175,650)","0","standard","I175";
;
CDS_LIB"standard"
BODY_TYPE"PLUMBING"
HDL_TAP"TRUE";
"B \NAC \NWC"5;
"S \NAC"
BN"2"91;
%"TAP"
"1","(4175,1050)","0","standard","I176";
;
CDS_LIB"standard"
BODY_TYPE"PLUMBING"
HDL_TAP"TRUE";
"B \NAC \NWC"5;
"S \NAC"
BN"4"119;
%"TAP"
"1","(4175,850)","0","standard","I177";
;
CDS_LIB"standard"
BODY_TYPE"PLUMBING"
HDL_TAP"TRUE";
"B \NAC \NWC"5;
"S \NAC"
BN"3"124;
%"TAP"
"1","(4375,200)","0","standard","I178";
;
CDS_LIB"standard"
BODY_TYPE"PLUMBING"
HDL_TAP"TRUE";
"B \NAC \NWC"6;
"S \NAC"
BN"0"120;
%"TAP"
"1","(4375,400)","0","standard","I179";
;
CDS_LIB"standard"
BODY_TYPE"PLUMBING"
HDL_TAP"TRUE";
"B \NAC \NWC"6;
"S \NAC"
BN"1"103;
%"TAP"
"1","(4375,600)","0","standard","I180";
;
CDS_LIB"standard"
BODY_TYPE"PLUMBING"
HDL_TAP"TRUE";
"B \NAC \NWC"6;
"S \NAC"
BN"2"122;
%"TAP"
"1","(4375,800)","0","standard","I181";
;
CDS_LIB"standard"
BODY_TYPE"PLUMBING"
HDL_TAP"TRUE";
"B \NAC \NWC"6;
"S \NAC"
BN"3"121;
%"TAP"
"1","(4375,1000)","0","standard","I182";
;
CDS_LIB"standard"
BODY_TYPE"PLUMBING"
HDL_TAP"TRUE";
"B \NAC \NWC"6;
"S \NAC"
BN"4"123;
%"TAP"
"1","(4175,1250)","0","standard","I183";
;
CDS_LIB"standard"
BODY_TYPE"PLUMBING"
HDL_TAP"TRUE";
"B \NAC \NWC"5;
"S \NAC"
BN"5"118;
%"TAP"
"1","(4175,1450)","0","standard","I184";
;
CDS_LIB"standard"
BODY_TYPE"PLUMBING"
HDL_TAP"TRUE";
"B \NAC \NWC"5;
"S \NAC"
BN"6"117;
%"TAP"
"1","(4175,1650)","0","standard","I185";
;
CDS_LIB"standard"
BODY_TYPE"PLUMBING"
HDL_TAP"TRUE";
"B \NAC \NWC"5;
"S \NAC"
BN"7"116;
%"TAP"
"1","(4375,1200)","0","standard","I186";
;
CDS_LIB"standard"
BODY_TYPE"PLUMBING"
HDL_TAP"TRUE";
"B \NAC \NWC"6;
"S \NAC"
BN"5"115;
%"TAP"
"1","(4375,1400)","0","standard","I187";
;
CDS_LIB"standard"
BODY_TYPE"PLUMBING"
HDL_TAP"TRUE";
"B \NAC \NWC"6;
"S \NAC"
BN"6"83;
%"TAP"
"1","(4375,1600)","0","standard","I188";
;
CDS_LIB"standard"
BODY_TYPE"PLUMBING"
HDL_TAP"TRUE";
"B \NAC \NWC"6;
"S \NAC"
BN"7"114;
%"TAP"
"1","(4175,2225)","0","standard","I191";
;
CDS_LIB"standard"
BODY_TYPE"PLUMBING"
HDL_TAP"TRUE";
"B \NAC \NWC"7;
"S \NAC"
BN"8"112;
%"TAP"
"1","(4175,2425)","0","standard","I192";
;
CDS_LIB"standard"
BODY_TYPE"PLUMBING"
HDL_TAP"TRUE";
"B \NAC \NWC"7;
"S \NAC"
BN"9"113;
%"TAP"
"1","(4175,2625)","0","standard","I193";
;
CDS_LIB"standard"
BODY_TYPE"PLUMBING"
HDL_TAP"TRUE";
"B \NAC \NWC"7;
"S \NAC"
BN"10"111;
%"TAP"
"1","(4175,2825)","0","standard","I194";
;
CDS_LIB"standard"
BODY_TYPE"PLUMBING"
HDL_TAP"TRUE";
"B \NAC \NWC"7;
"S \NAC"
BN"11"110;
%"TAP"
"1","(4175,3025)","0","standard","I195";
;
CDS_LIB"standard"
BODY_TYPE"PLUMBING"
HDL_TAP"TRUE";
"B \NAC \NWC"7;
"S \NAC"
BN"12"87;
%"TAP"
"1","(4375,2175)","0","standard","I196";
;
CDS_LIB"standard"
BODY_TYPE"PLUMBING"
HDL_TAP"TRUE";
"B \NAC \NWC"8;
"S \NAC"
BN"8"109;
%"TAP"
"1","(4375,2375)","0","standard","I197";
;
CDS_LIB"standard"
BODY_TYPE"PLUMBING"
HDL_TAP"TRUE";
"B \NAC \NWC"8;
"S \NAC"
BN"9"92;
%"TAP"
"1","(4375,2575)","0","standard","I198";
;
CDS_LIB"standard"
BODY_TYPE"PLUMBING"
HDL_TAP"TRUE";
"B \NAC \NWC"8;
"S \NAC"
BN"10"94;
%"TAP"
"1","(4375,2775)","0","standard","I199";
;
CDS_LIB"standard"
BODY_TYPE"PLUMBING"
HDL_TAP"TRUE";
"B \NAC \NWC"8;
"S \NAC"
BN"11"101;
%"TAP"
"1","(4375,2975)","0","standard","I200";
;
CDS_LIB"standard"
BODY_TYPE"PLUMBING"
HDL_TAP"TRUE";
"B \NAC \NWC"8;
"S \NAC"
BN"12"88;
%"TAP"
"1","(4175,3225)","0","standard","I201";
;
CDS_LIB"standard"
BODY_TYPE"PLUMBING"
HDL_TAP"TRUE";
"B \NAC \NWC"7;
"S \NAC"
BN"13"82;
%"TAP"
"1","(4175,3625)","0","standard","I202";
;
CDS_LIB"standard"
BODY_TYPE"PLUMBING"
HDL_TAP"TRUE";
"B \NAC \NWC"7;
"S \NAC"
BN"15"107;
%"TAP"
"1","(4175,3425)","0","standard","I203";
;
CDS_LIB"standard"
BODY_TYPE"PLUMBING"
HDL_TAP"TRUE";
"B \NAC \NWC"7;
"S \NAC"
BN"14"108;
%"TAP"
"1","(4375,3175)","0","standard","I204";
;
CDS_LIB"standard"
BODY_TYPE"PLUMBING"
HDL_TAP"TRUE";
"B \NAC \NWC"8;
"S \NAC"
BN"13"104;
%"TAP"
"1","(4375,3375)","0","standard","I205";
;
CDS_LIB"standard"
BODY_TYPE"PLUMBING"
HDL_TAP"TRUE";
"B \NAC \NWC"8;
"S \NAC"
BN"14"105;
%"TAP"
"1","(4375,3575)","0","standard","I206";
;
CDS_LIB"standard"
BODY_TYPE"PLUMBING"
HDL_TAP"TRUE";
"B \NAC \NWC"8;
"S \NAC"
BN"15"106;
%"TAP"
"1","(-1925,175)","2","standard","I213";
;
CDS_LIB"standard"
BODY_TYPE"PLUMBING"
HDL_TAP"TRUE";
"B \NAC \NWC"10;
"S \NAC"
BN"0"79;
%"TAP"
"1","(-1925,375)","2","standard","I214";
;
CDS_LIB"standard"
BODY_TYPE"PLUMBING"
HDL_TAP"TRUE";
"B \NAC \NWC"10;
"S \NAC"
BN"1"73;
%"TAP"
"1","(-1675,225)","2","standard","I215";
;
CDS_LIB"standard"
BODY_TYPE"PLUMBING"
HDL_TAP"TRUE";
"B \NAC \NWC"9;
"S \NAC"
BN"0"68;
%"TAP"
"1","(-1675,425)","2","standard","I216";
;
CDS_LIB"standard"
BODY_TYPE"PLUMBING"
HDL_TAP"TRUE";
"B \NAC \NWC"9;
"S \NAC"
BN"1"75;
%"TAP"
"1","(-1925,575)","2","standard","I217";
;
CDS_LIB"standard"
BODY_TYPE"PLUMBING"
HDL_TAP"TRUE";
"B \NAC \NWC"10;
"S \NAC"
BN"2"76;
%"TAP"
"1","(-1925,775)","2","standard","I218";
;
CDS_LIB"standard"
BODY_TYPE"PLUMBING"
HDL_TAP"TRUE";
"B \NAC \NWC"10;
"S \NAC"
BN"3"77;
%"TAP"
"1","(-1925,975)","2","standard","I219";
;
CDS_LIB"standard"
BODY_TYPE"PLUMBING"
HDL_TAP"TRUE";
"B \NAC \NWC"10;
"S \NAC"
BN"4"78;
%"TAP"
"1","(-1675,625)","2","standard","I220";
;
CDS_LIB"standard"
BODY_TYPE"PLUMBING"
HDL_TAP"TRUE";
"B \NAC \NWC"9;
"S \NAC"
BN"2"80;
%"TAP"
"1","(-1675,825)","2","standard","I221";
;
CDS_LIB"standard"
BODY_TYPE"PLUMBING"
HDL_TAP"TRUE";
"B \NAC \NWC"9;
"S \NAC"
BN"3"69;
%"TAP"
"1","(-1925,1175)","2","standard","I222";
;
CDS_LIB"standard"
BODY_TYPE"PLUMBING"
HDL_TAP"TRUE";
"B \NAC \NWC"10;
"S \NAC"
BN"5"71;
%"TAP"
"1","(-1925,1375)","2","standard","I223";
;
CDS_LIB"standard"
BODY_TYPE"PLUMBING"
HDL_TAP"TRUE";
"B \NAC \NWC"10;
"S \NAC"
BN"6"70;
%"TAP"
"1","(-1675,1225)","2","standard","I224";
;
CDS_LIB"standard"
BODY_TYPE"PLUMBING"
HDL_TAP"TRUE";
"B \NAC \NWC"9;
"S \NAC"
BN"5"72;
%"TAP"
"1","(-1675,1025)","2","standard","I225";
;
CDS_LIB"standard"
BODY_TYPE"PLUMBING"
HDL_TAP"TRUE";
"B \NAC \NWC"9;
"S \NAC"
BN"4"67;
%"TAP"
"1","(-1675,1425)","2","standard","I226";
;
CDS_LIB"standard"
BODY_TYPE"PLUMBING"
HDL_TAP"TRUE";
"B \NAC \NWC"9;
"S \NAC"
BN"6"66;
%"TAP"
"1","(-1925,1575)","2","standard","I227";
;
CDS_LIB"standard"
BODY_TYPE"PLUMBING"
HDL_TAP"TRUE";
"B \NAC \NWC"10;
"S \NAC"
BN"7"25;
%"TAP"
"1","(-1675,1625)","2","standard","I228";
;
CDS_LIB"standard"
BODY_TYPE"PLUMBING"
HDL_TAP"TRUE";
"B \NAC \NWC"9;
"S \NAC"
BN"7"74;
%"Q_CAP_DIFFBUS"
"2","(-950,225)","2","pure_quanta","I229";
;
PART_NUMBER"SP_CH4221MEE01"
VALUE"DIFF BUS_0.22UF"
$LOCATION"C740"
PIN_NAMES_ROTATE"TRUE"
CDS_LIB"pure_quanta"
CDS_LMAN_SYM_OUTLINE"-25,50,25,-50"
VOLTAGE"6.3V"
MATERIAL"X6S"
PACK_TYPE"C0201"
TOLERANCE"20%"
$LOCATION"C740"
CDS_LOCATION"C740"
$SEC"1"
CDS_SEC"1";
"2"
$PN"2"68;
"1"
$PN"1"61;
%"Q_CAP_DIFFBUS"
"2","(-950,175)","2","pure_quanta","I230";
;
PART_NUMBER"SP_CH4221MEE01"
VALUE"DIFF BUS_0.22UF"
$LOCATION"C741"
PIN_NAMES_ROTATE"TRUE"
CDS_LIB"pure_quanta"
CDS_LMAN_SYM_OUTLINE"-25,50,25,-50"
VOLTAGE"6.3V"
MATERIAL"X6S"
PACK_TYPE"C0201"
TOLERANCE"20%"
$LOCATION"C741"
CDS_LOCATION"C741"
$SEC"1"
CDS_SEC"1";
"2"
$PN"2"79;
"1"
$PN"1"65;
%"Q_CAP_DIFFBUS"
"2","(-950,375)","2","pure_quanta","I231";
;
PART_NUMBER"SP_CH4221MEE01"
VALUE"DIFF BUS_0.22UF"
$LOCATION"C739"
PIN_NAMES_ROTATE"TRUE"
CDS_LIB"pure_quanta"
CDS_LMAN_SYM_OUTLINE"-25,50,25,-50"
VOLTAGE"6.3V"
MATERIAL"X6S"
PACK_TYPE"C0201"
TOLERANCE"20%"
$LOCATION"C739"
CDS_LOCATION"C739"
$SEC"1"
CDS_SEC"1";
"2"
$PN"2"73;
"1"
$PN"1"59;
%"Q_CAP_DIFFBUS"
"2","(-950,425)","2","pure_quanta","I232";
;
PART_NUMBER"SP_CH4221MEE01"
VALUE"DIFF BUS_0.22UF"
$LOCATION"C738"
PIN_NAMES_ROTATE"TRUE"
CDS_LMAN_SYM_OUTLINE"-25,50,25,-50"
CDS_LIB"pure_quanta"
VOLTAGE"6.3V"
MATERIAL"X6S"
PACK_TYPE"C0201"
TOLERANCE"20%"
$LOCATION"C738"
CDS_LOCATION"C738"
$SEC"1"
CDS_SEC"1";
"2"
$PN"2"75;
"1"
$PN"1"62;
%"Q_CAP_DIFFBUS"
"2","(-950,575)","2","pure_quanta","I233";
;
PART_NUMBER"SP_CH4221MEE01"
VALUE"DIFF BUS_0.22UF"
$LOCATION"C737"
PIN_NAMES_ROTATE"TRUE"
CDS_LIB"pure_quanta"
CDS_LMAN_SYM_OUTLINE"-25,50,25,-50"
VOLTAGE"6.3V"
MATERIAL"X6S"
PACK_TYPE"C0201"
TOLERANCE"20%"
$LOCATION"C737"
CDS_LOCATION"C737"
$SEC"1"
CDS_SEC"1";
"2"
$PN"2"76;
"1"
$PN"1"64;
%"Q_CAP_DIFFBUS"
"2","(-950,625)","2","pure_quanta","I234";
;
PART_NUMBER"SP_CH4221MEE01"
VALUE"DIFF BUS_0.22UF"
$LOCATION"C736"
PIN_NAMES_ROTATE"TRUE"
CDS_LIB"pure_quanta"
CDS_LMAN_SYM_OUTLINE"-25,50,25,-50"
VOLTAGE"6.3V"
MATERIAL"X6S"
PACK_TYPE"C0201"
TOLERANCE"20%"
$LOCATION"C736"
CDS_LOCATION"C736"
$SEC"1"
CDS_SEC"1";
"2"
$PN"2"80;
"1"
$PN"1"63;
%"Q_CAP_DIFFBUS"
"2","(-950,825)","2","pure_quanta","I235";
;
PART_NUMBER"SP_CH4221MEE01"
VALUE"DIFF BUS_0.22UF"
$LOCATION"C734"
PIN_NAMES_ROTATE"TRUE"
CDS_LMAN_SYM_OUTLINE"-25,50,25,-50"
CDS_LIB"pure_quanta"
VOLTAGE"6.3V"
MATERIAL"X6S"
PACK_TYPE"C0201"
TOLERANCE"20%"
$LOCATION"C734"
CDS_LOCATION"C734"
$SEC"1"
CDS_SEC"1";
"2"
$PN"2"69;
"1"
$PN"1"60;
%"Q_CAP_DIFFBUS"
"2","(-950,775)","2","pure_quanta","I236";
;
PART_NUMBER"SP_CH4221MEE01"
VALUE"DIFF BUS_0.22UF"
$LOCATION"C735"
PIN_NAMES_ROTATE"TRUE"
CDS_LMAN_SYM_OUTLINE"-25,50,25,-50"
CDS_LIB"pure_quanta"
VOLTAGE"6.3V"
MATERIAL"X6S"
PACK_TYPE"C0201"
TOLERANCE"20%"
$LOCATION"C735"
CDS_LOCATION"C735"
$SEC"1"
CDS_SEC"1";
"2"
$PN"2"77;
"1"
$PN"1"58;
%"Q_CAP_DIFFBUS"
"2","(-950,975)","2","pure_quanta","I237";
;
PART_NUMBER"SP_CH4221MEE01"
VALUE"DIFF BUS_0.22UF"
$LOCATION"C733"
PIN_NAMES_ROTATE"TRUE"
CDS_LIB"pure_quanta"
CDS_LMAN_SYM_OUTLINE"-25,50,25,-50"
VOLTAGE"6.3V"
MATERIAL"X6S"
PACK_TYPE"C0201"
TOLERANCE"20%"
$LOCATION"C733"
CDS_LOCATION"C733"
$SEC"1"
CDS_SEC"1";
"2"
$PN"2"78;
"1"
$PN"1"31;
%"TAP"
"1","(-400,225)","0","standard","I238";
;
CDS_LIB"standard"
BODY_TYPE"PLUMBING"
HDL_TAP"TRUE";
"B \NAC \NWC"12;
"S \NAC"
BN"0"61;
%"TAP"
"1","(-400,425)","0","standard","I239";
;
CDS_LIB"standard"
BODY_TYPE"PLUMBING"
HDL_TAP"TRUE";
"B \NAC \NWC"12;
"S \NAC"
BN"1"62;
%"TAP"
"1","(-200,175)","0","standard","I240";
;
CDS_LIB"standard"
BODY_TYPE"PLUMBING"
HDL_TAP"TRUE";
"B \NAC \NWC"11;
"S \NAC"
BN"0"65;
%"TAP"
"1","(-200,375)","0","standard","I241";
;
CDS_LIB"standard"
BODY_TYPE"PLUMBING"
HDL_TAP"TRUE";
"B \NAC \NWC"11;
"S \NAC"
BN"1"59;
%"TAP"
"1","(-400,625)","0","standard","I242";
;
CDS_LIB"standard"
BODY_TYPE"PLUMBING"
HDL_TAP"TRUE";
"B \NAC \NWC"12;
"S \NAC"
BN"2"63;
%"TAP"
"1","(-400,825)","0","standard","I243";
;
CDS_LIB"standard"
BODY_TYPE"PLUMBING"
HDL_TAP"TRUE";
"B \NAC \NWC"12;
"S \NAC"
BN"3"60;
%"TAP"
"1","(-200,575)","0","standard","I244";
;
CDS_LIB"standard"
BODY_TYPE"PLUMBING"
HDL_TAP"TRUE";
"B \NAC \NWC"11;
"S \NAC"
BN"2"64;
%"TAP"
"1","(-200,775)","0","standard","I245";
;
CDS_LIB"standard"
BODY_TYPE"PLUMBING"
HDL_TAP"TRUE";
"B \NAC \NWC"11;
"S \NAC"
BN"3"58;
%"Q_CAP_DIFFBUS"
"2","(-950,1025)","2","pure_quanta","I246";
;
PART_NUMBER"SP_CH4221MEE01"
VALUE"DIFF BUS_0.22UF"
$LOCATION"C732"
PIN_NAMES_ROTATE"TRUE"
CDS_LIB"pure_quanta"
CDS_LMAN_SYM_OUTLINE"-25,50,25,-50"
VOLTAGE"6.3V"
MATERIAL"X6S"
PACK_TYPE"C0201"
TOLERANCE"20%"
$LOCATION"C732"
CDS_LOCATION"C732"
$SEC"1"
CDS_SEC"1";
"2"
$PN"2"67;
"1"
$PN"1"57;
%"Q_CAP_DIFFBUS"
"2","(-950,1175)","2","pure_quanta","I247";
;
PART_NUMBER"SP_CH4221MEE01"
VALUE"DIFF BUS_0.22UF"
$LOCATION"C731"
PIN_NAMES_ROTATE"TRUE"
CDS_LIB"pure_quanta"
CDS_LMAN_SYM_OUTLINE"-25,50,25,-50"
VOLTAGE"6.3V"
MATERIAL"X6S"
PACK_TYPE"C0201"
TOLERANCE"20%"
$LOCATION"C731"
CDS_LOCATION"C731"
$SEC"1"
CDS_SEC"1";
"2"
$PN"2"71;
"1"
$PN"1"30;
%"Q_CAP_DIFFBUS"
"2","(-950,1225)","2","pure_quanta","I248";
;
PART_NUMBER"SP_CH4221MEE01"
VALUE"DIFF BUS_0.22UF"
$LOCATION"C730"
PIN_NAMES_ROTATE"TRUE"
CDS_LIB"pure_quanta"
CDS_LMAN_SYM_OUTLINE"-25,50,25,-50"
VOLTAGE"6.3V"
MATERIAL"X6S"
PACK_TYPE"C0201"
TOLERANCE"20%"
$LOCATION"C730"
CDS_LOCATION"C730"
$SEC"1"
CDS_SEC"1";
"2"
$PN"2"72;
"1"
$PN"1"55;
%"Q_CAP_DIFFBUS"
"2","(-950,1375)","2","pure_quanta","I249";
;
PART_NUMBER"SP_CH4221MEE01"
VALUE"DIFF BUS_0.22UF"
$LOCATION"C729"
PIN_NAMES_ROTATE"TRUE"
CDS_LIB"pure_quanta"
CDS_LMAN_SYM_OUTLINE"-25,50,25,-50"
VOLTAGE"6.3V"
MATERIAL"X6S"
PACK_TYPE"C0201"
TOLERANCE"20%"
$LOCATION"C729"
CDS_LOCATION"C729"
$SEC"1"
CDS_SEC"1";
"2"
$PN"2"70;
"1"
$PN"1"29;
%"Q_CAP_DIFFBUS"
"2","(-950,1425)","2","pure_quanta","I250";
;
PART_NUMBER"SP_CH4221MEE01"
VALUE"DIFF BUS_0.22UF"
$LOCATION"C728"
PIN_NAMES_ROTATE"TRUE"
CDS_LIB"pure_quanta"
CDS_LMAN_SYM_OUTLINE"-25,50,25,-50"
VOLTAGE"6.3V"
MATERIAL"X6S"
PACK_TYPE"C0201"
TOLERANCE"20%"
$LOCATION"C728"
CDS_LOCATION"C728"
$SEC"1"
CDS_SEC"1";
"2"
$PN"2"66;
"1"
$PN"1"28;
%"Q_CAP_DIFFBUS"
"2","(-950,1575)","2","pure_quanta","I251";
;
PART_NUMBER"SP_CH4221MEE01"
VALUE"DIFF BUS_0.22UF"
$LOCATION"C727"
PIN_NAMES_ROTATE"TRUE"
CDS_LIB"pure_quanta"
CDS_LMAN_SYM_OUTLINE"-25,50,25,-50"
VOLTAGE"6.3V"
MATERIAL"X6S"
PACK_TYPE"C0201"
TOLERANCE"20%"
$LOCATION"C727"
CDS_LOCATION"C727"
$SEC"1"
CDS_SEC"1";
"2"
$PN"2"25;
"1"
$PN"1"27;
%"TAP"
"1","(-400,1025)","0","standard","I252";
;
CDS_LIB"standard"
BODY_TYPE"PLUMBING"
HDL_TAP"TRUE";
"B \NAC \NWC"12;
"S \NAC"
BN"4"57;
%"TAP"
"1","(-400,1425)","0","standard","I253";
;
CDS_LIB"standard"
BODY_TYPE"PLUMBING"
HDL_TAP"TRUE";
"B \NAC \NWC"12;
"S \NAC"
BN"6"28;
%"TAP"
"1","(-200,1175)","0","standard","I254";
;
CDS_LIB"standard"
BODY_TYPE"PLUMBING"
HDL_TAP"TRUE";
"B \NAC \NWC"11;
"S \NAC"
BN"5"30;
%"TAP"
"1","(-200,1375)","0","standard","I255";
;
CDS_LIB"standard"
BODY_TYPE"PLUMBING"
HDL_TAP"TRUE";
"B \NAC \NWC"11;
"S \NAC"
BN"6"29;
%"TAP"
"1","(-400,1625)","0","standard","I256";
;
CDS_LIB"standard"
BODY_TYPE"PLUMBING"
HDL_TAP"TRUE";
"B \NAC \NWC"12;
"S \NAC"
BN"7"56;
%"TAP"
"1","(-200,1575)","0","standard","I257";
;
CDS_LIB"standard"
BODY_TYPE"PLUMBING"
HDL_TAP"TRUE";
"B \NAC \NWC"11;
"S \NAC"
BN"7"27;
%"TAP"
"1","(-1925,2150)","2","standard","I258";
;
CDS_LIB"standard"
BODY_TYPE"PLUMBING"
HDL_TAP"TRUE";
"B \NAC \NWC"14;
"S \NAC"
BN"8"26;
%"TAP"
"1","(-1925,2350)","2","standard","I259";
;
CDS_LIB"standard"
BODY_TYPE"PLUMBING"
HDL_TAP"TRUE";
"B \NAC \NWC"14;
"S \NAC"
BN"9"52;
%"TAP"
"1","(-1675,2200)","2","standard","I260";
;
CDS_LIB"standard"
BODY_TYPE"PLUMBING"
HDL_TAP"TRUE";
"B \NAC \NWC"13;
"S \NAC"
BN"8"50;
%"TAP"
"1","(-1675,2400)","2","standard","I261";
;
CDS_LIB"standard"
BODY_TYPE"PLUMBING"
HDL_TAP"TRUE";
"B \NAC \NWC"13;
"S \NAC"
BN"9"24;
%"TAP"
"1","(-1925,2750)","2","standard","I262";
;
CDS_LIB"standard"
BODY_TYPE"PLUMBING"
HDL_TAP"TRUE";
"B \NAC \NWC"14;
"S \NAC"
BN"11"23;
%"TAP"
"1","(-1925,2550)","2","standard","I263";
;
CDS_LIB"standard"
BODY_TYPE"PLUMBING"
HDL_TAP"TRUE";
"B \NAC \NWC"14;
"S \NAC"
BN"10"51;
%"TAP"
"1","(-1925,2950)","2","standard","I264";
;
CDS_LIB"standard"
BODY_TYPE"PLUMBING"
HDL_TAP"TRUE";
"B \NAC \NWC"14;
"S \NAC"
BN"12"22;
%"TAP"
"1","(-1675,2600)","2","standard","I265";
;
CDS_LIB"standard"
BODY_TYPE"PLUMBING"
HDL_TAP"TRUE";
"B \NAC \NWC"13;
"S \NAC"
BN"10"54;
%"TAP"
"1","(-1675,2800)","2","standard","I266";
;
CDS_LIB"standard"
BODY_TYPE"PLUMBING"
HDL_TAP"TRUE";
"B \NAC \NWC"13;
"S \NAC"
BN"11"53;
%"TAP"
"1","(-1675,3000)","2","standard","I267";
;
CDS_LIB"standard"
BODY_TYPE"PLUMBING"
HDL_TAP"TRUE";
"B \NAC \NWC"13;
"S \NAC"
BN"12"21;
%"TAP"
"1","(-1925,3150)","2","standard","I268";
;
CDS_LIB"standard"
BODY_TYPE"PLUMBING"
HDL_TAP"TRUE";
"B \NAC \NWC"14;
"S \NAC"
BN"13"20;
%"TAP"
"1","(-1925,3350)","2","standard","I269";
;
CDS_LIB"standard"
BODY_TYPE"PLUMBING"
HDL_TAP"TRUE";
"B \NAC \NWC"14;
"S \NAC"
BN"14"19;
%"TAP"
"1","(-1925,3550)","2","standard","I270";
;
CDS_LIB"standard"
BODY_TYPE"PLUMBING"
HDL_TAP"TRUE";
"B \NAC \NWC"14;
"S \NAC"
BN"15"17;
%"TAP"
"1","(-1675,3200)","2","standard","I271";
;
CDS_LIB"standard"
BODY_TYPE"PLUMBING"
HDL_TAP"TRUE";
"B \NAC \NWC"13;
"S \NAC"
BN"13"48;
%"TAP"
"1","(-1675,3400)","2","standard","I272";
;
CDS_LIB"standard"
BODY_TYPE"PLUMBING"
HDL_TAP"TRUE";
"B \NAC \NWC"13;
"S \NAC"
BN"14"18;
%"TAP"
"1","(-1675,3600)","2","standard","I273";
;
CDS_LIB"standard"
BODY_TYPE"PLUMBING"
HDL_TAP"TRUE";
"B \NAC \NWC"13;
"S \NAC"
BN"15"49;
%"Q_CAP_DIFFBUS"
"2","(-950,2150)","2","pure_quanta","I274";
;
PART_NUMBER"SP_CH4221MEE01"
VALUE"DIFF BUS_0.22UF"
$LOCATION"C725"
CDS_LMAN_SYM_OUTLINE"-25,50,25,-50"
CDS_LIB"pure_quanta"
PIN_NAMES_ROTATE"TRUE"
VOLTAGE"6.3V"
MATERIAL"X6S"
PACK_TYPE"C0201"
TOLERANCE"20%"
$LOCATION"C725"
CDS_LOCATION"C725"
$SEC"1"
CDS_SEC"1";
"2"
$PN"2"26;
"1"
$PN"1"38;
%"Q_CAP_DIFFBUS"
"2","(-950,2200)","2","pure_quanta","I275";
;
PART_NUMBER"SP_CH4221MEE01"
VALUE"DIFF BUS_0.22UF"
$LOCATION"C724"
CDS_LMAN_SYM_OUTLINE"-25,50,25,-50"
CDS_LIB"pure_quanta"
PIN_NAMES_ROTATE"TRUE"
VOLTAGE"6.3V"
MATERIAL"X6S"
PACK_TYPE"C0201"
TOLERANCE"20%"
$LOCATION"C724"
CDS_LOCATION"C724"
$SEC"1"
CDS_SEC"1";
"2"
$PN"2"50;
"1"
$PN"1"45;
%"Q_CAP_DIFFBUS"
"2","(-950,2400)","2","pure_quanta","I276";
;
PART_NUMBER"SP_CH4221MEE01"
VALUE"DIFF BUS_0.22UF"
$LOCATION"C722"
CDS_LIB"pure_quanta"
CDS_LMAN_SYM_OUTLINE"-25,50,25,-50"
PIN_NAMES_ROTATE"TRUE"
VOLTAGE"6.3V"
MATERIAL"X6S"
PACK_TYPE"C0201"
TOLERANCE"20%"
$LOCATION"C722"
CDS_LOCATION"C722"
$SEC"1"
CDS_SEC"1";
"2"
$PN"2"24;
"1"
$PN"1"42;
%"Q_CAP_DIFFBUS"
"2","(-950,2350)","2","pure_quanta","I277";
;
PART_NUMBER"SP_CH4221MEE01"
VALUE"DIFF BUS_0.22UF"
$LOCATION"C723"
CDS_LMAN_SYM_OUTLINE"-25,50,25,-50"
CDS_LIB"pure_quanta"
PIN_NAMES_ROTATE"TRUE"
VOLTAGE"6.3V"
MATERIAL"X6S"
PACK_TYPE"C0201"
TOLERANCE"20%"
$LOCATION"C723"
CDS_LOCATION"C723"
$SEC"1"
CDS_SEC"1";
"2"
$PN"2"52;
"1"
$PN"1"40;
%"Q_CAP_DIFFBUS"
"2","(-950,2550)","2","pure_quanta","I278";
;
PART_NUMBER"SP_CH4221MEE01"
VALUE"DIFF BUS_0.22UF"
$LOCATION"C721"
CDS_LMAN_SYM_OUTLINE"-25,50,25,-50"
CDS_LIB"pure_quanta"
PIN_NAMES_ROTATE"TRUE"
VOLTAGE"6.3V"
MATERIAL"X6S"
PACK_TYPE"C0201"
TOLERANCE"20%"
$LOCATION"C721"
CDS_LOCATION"C721"
$SEC"1"
CDS_SEC"1";
"2"
$PN"2"51;
"1"
$PN"1"39;
%"Q_CAP_DIFFBUS"
"2","(-950,2600)","2","pure_quanta","I279";
;
PART_NUMBER"SP_CH4221MEE01"
VALUE"DIFF BUS_0.22UF"
$LOCATION"C720"
CDS_LMAN_SYM_OUTLINE"-25,50,25,-50"
CDS_LIB"pure_quanta"
PIN_NAMES_ROTATE"TRUE"
VOLTAGE"6.3V"
MATERIAL"X6S"
PACK_TYPE"C0201"
TOLERANCE"20%"
$LOCATION"C720"
CDS_LOCATION"C720"
$SEC"1"
CDS_SEC"1";
"2"
$PN"2"54;
"1"
$PN"1"44;
%"Q_CAP_DIFFBUS"
"2","(-950,2750)","2","pure_quanta","I280";
;
PART_NUMBER"SP_CH4221MEE01"
VALUE"DIFF BUS_0.22UF"
$LOCATION"C719"
CDS_LIB"pure_quanta"
CDS_LMAN_SYM_OUTLINE"-25,50,25,-50"
PIN_NAMES_ROTATE"TRUE"
VOLTAGE"6.3V"
MATERIAL"X6S"
PACK_TYPE"C0201"
TOLERANCE"20%"
$LOCATION"C719"
CDS_LOCATION"C719"
$SEC"1"
CDS_SEC"1";
"2"
$PN"2"23;
"1"
$PN"1"41;
%"Q_CAP_DIFFBUS"
"2","(-950,2800)","2","pure_quanta","I281";
;
PART_NUMBER"SP_CH4221MEE01"
VALUE"DIFF BUS_0.22UF"
$LOCATION"C718"
CDS_LIB"pure_quanta"
CDS_LMAN_SYM_OUTLINE"-25,50,25,-50"
PIN_NAMES_ROTATE"TRUE"
VOLTAGE"6.3V"
MATERIAL"X6S"
PACK_TYPE"C0201"
TOLERANCE"20%"
$LOCATION"C718"
CDS_LOCATION"C718"
$SEC"1"
CDS_SEC"1";
"2"
$PN"2"53;
"1"
$PN"1"46;
%"Q_CAP_DIFFBUS"
"2","(-950,2950)","2","pure_quanta","I282";
;
PART_NUMBER"SP_CH4221MEE01"
VALUE"DIFF BUS_0.22UF"
$LOCATION"C717"
CDS_LMAN_SYM_OUTLINE"-25,50,25,-50"
CDS_LIB"pure_quanta"
PIN_NAMES_ROTATE"TRUE"
VOLTAGE"6.3V"
MATERIAL"X6S"
PACK_TYPE"C0201"
TOLERANCE"20%"
$LOCATION"C717"
CDS_LOCATION"C717"
$SEC"1"
CDS_SEC"1";
"2"
$PN"2"22;
"1"
$PN"1"47;
%"Q_CAP_DIFFBUS"
"2","(-950,3000)","2","pure_quanta","I283";
;
PART_NUMBER"SP_CH4221MEE01"
VALUE"DIFF BUS_0.22UF"
$LOCATION"C716"
CDS_LMAN_SYM_OUTLINE"-25,50,25,-50"
CDS_LIB"pure_quanta"
PIN_NAMES_ROTATE"TRUE"
VOLTAGE"6.3V"
MATERIAL"X6S"
PACK_TYPE"C0201"
TOLERANCE"20%"
$LOCATION"C716"
CDS_LOCATION"C716"
$SEC"1"
CDS_SEC"1";
"2"
$PN"2"21;
"1"
$PN"1"43;
%"TAP"
"1","(-400,2200)","0","standard","I284";
;
CDS_LIB"standard"
BODY_TYPE"PLUMBING"
HDL_TAP"TRUE";
"B \NAC \NWC"16;
"S \NAC"
BN"8"45;
%"TAP"
"1","(-400,2400)","0","standard","I285";
;
CDS_LIB"standard"
BODY_TYPE"PLUMBING"
HDL_TAP"TRUE";
"B \NAC \NWC"16;
"S \NAC"
BN"9"42;
%"TAP"
"1","(-200,2150)","0","standard","I286";
;
CDS_LIB"standard"
BODY_TYPE"PLUMBING"
HDL_TAP"TRUE";
"B \NAC \NWC"15;
"S \NAC"
BN"8"38;
%"TAP"
"1","(-200,2350)","0","standard","I287";
;
CDS_LIB"standard"
BODY_TYPE"PLUMBING"
HDL_TAP"TRUE";
"B \NAC \NWC"15;
"S \NAC"
BN"9"40;
%"TAP"
"1","(-400,2600)","0","standard","I288";
;
CDS_LIB"standard"
BODY_TYPE"PLUMBING"
HDL_TAP"TRUE";
"B \NAC \NWC"16;
"S \NAC"
BN"10"44;
%"TAP"
"1","(-400,3000)","0","standard","I289";
;
CDS_LIB"standard"
BODY_TYPE"PLUMBING"
HDL_TAP"TRUE";
"B \NAC \NWC"16;
"S \NAC"
BN"12"43;
%"TAP"
"1","(-400,2800)","0","standard","I290";
;
CDS_LIB"standard"
BODY_TYPE"PLUMBING"
HDL_TAP"TRUE";
"B \NAC \NWC"16;
"S \NAC"
BN"11"46;
%"TAP"
"1","(-200,2550)","0","standard","I291";
;
CDS_LIB"standard"
BODY_TYPE"PLUMBING"
HDL_TAP"TRUE";
"B \NAC \NWC"15;
"S \NAC"
BN"10"39;
%"TAP"
"1","(-200,2750)","0","standard","I292";
;
CDS_LIB"standard"
BODY_TYPE"PLUMBING"
HDL_TAP"TRUE";
"B \NAC \NWC"15;
"S \NAC"
BN"11"41;
%"TAP"
"1","(-200,2950)","0","standard","I293";
;
CDS_LIB"standard"
BODY_TYPE"PLUMBING"
HDL_TAP"TRUE";
"B \NAC \NWC"15;
"S \NAC"
BN"12"47;
%"Q_CAP_DIFFBUS"
"2","(-950,3150)","2","pure_quanta","I294";
;
PART_NUMBER"SP_CH4221MEE01"
VALUE"DIFF BUS_0.22UF"
$LOCATION"C715"
CDS_LMAN_SYM_OUTLINE"-25,50,25,-50"
CDS_LIB"pure_quanta"
PIN_NAMES_ROTATE"TRUE"
VOLTAGE"6.3V"
MATERIAL"X6S"
PACK_TYPE"C0201"
TOLERANCE"20%"
$LOCATION"C715"
CDS_LOCATION"C715"
$SEC"1"
CDS_SEC"1";
"2"
$PN"2"20;
"1"
$PN"1"32;
%"Q_CAP_DIFFBUS"
"2","(-950,3200)","2","pure_quanta","I295";
;
PART_NUMBER"SP_CH4221MEE01"
VALUE"DIFF BUS_0.22UF"
$LOCATION"C714"
CDS_LMAN_SYM_OUTLINE"-25,50,25,-50"
CDS_LIB"pure_quanta"
PIN_NAMES_ROTATE"TRUE"
VOLTAGE"6.3V"
MATERIAL"X6S"
PACK_TYPE"C0201"
TOLERANCE"20%"
$LOCATION"C714"
CDS_LOCATION"C714"
$SEC"1"
CDS_SEC"1";
"2"
$PN"2"48;
"1"
$PN"1"36;
%"Q_CAP_DIFFBUS"
"2","(-950,3400)","2","pure_quanta","I296";
;
PART_NUMBER"SP_CH4221MEE01"
VALUE"DIFF BUS_0.22UF"
$LOCATION"C712"
CDS_LMAN_SYM_OUTLINE"-25,50,25,-50"
CDS_LIB"pure_quanta"
PIN_NAMES_ROTATE"TRUE"
VOLTAGE"6.3V"
MATERIAL"X6S"
PACK_TYPE"C0201"
TOLERANCE"20%"
$LOCATION"C712"
CDS_LOCATION"C712"
$SEC"1"
CDS_SEC"1";
"2"
$PN"2"18;
"1"
$PN"1"37;
%"Q_CAP_DIFFBUS"
"2","(-950,3350)","2","pure_quanta","I297";
;
PART_NUMBER"SP_CH4221MEE01"
VALUE"DIFF BUS_0.22UF"
$LOCATION"C713"
CDS_LMAN_SYM_OUTLINE"-25,50,25,-50"
CDS_LIB"pure_quanta"
PIN_NAMES_ROTATE"TRUE"
VOLTAGE"6.3V"
MATERIAL"X6S"
PACK_TYPE"C0201"
TOLERANCE"20%"
$LOCATION"C713"
CDS_LOCATION"C713"
$SEC"1"
CDS_SEC"1";
"2"
$PN"2"19;
"1"
$PN"1"34;
%"Q_CAP_DIFFBUS"
"2","(-950,3550)","2","pure_quanta","I298";
;
PART_NUMBER"SP_CH4221MEE01"
VALUE"DIFF BUS_0.22UF"
$LOCATION"C711"
CDS_LMAN_SYM_OUTLINE"-25,50,25,-50"
CDS_LIB"pure_quanta"
PIN_NAMES_ROTATE"TRUE"
VOLTAGE"6.3V"
MATERIAL"X6S"
PACK_TYPE"C0201"
TOLERANCE"20%"
$LOCATION"C711"
CDS_LOCATION"C711"
$SEC"1"
CDS_SEC"1";
"2"
$PN"2"17;
"1"
$PN"1"33;
%"Q_CAP_DIFFBUS"
"2","(-950,3600)","2","pure_quanta","I299";
;
PART_NUMBER"SP_CH4221MEE01"
VOLTAGE"6.3V"
TOLERANCE"20%"
VALUE"DIFF BUS_0.22UF"
PACK_TYPE"C0201"
MATERIAL"X6S"
$LOCATION"C710"
CDS_LIB"pure_quanta"
CDS_LMAN_SYM_OUTLINE"-25,50,25,-50"
PIN_NAMES_ROTATE"TRUE"
$LOCATION"C710"
CDS_LOCATION"C710"
$SEC"1"
CDS_SEC"1";
"2"
$PN"2"49;
"1"
$PN"1"35;
%"TAP"
"1","(-400,3200)","0","standard","I300";
;
CDS_LIB"standard"
BODY_TYPE"PLUMBING"
HDL_TAP"TRUE";
"B \NAC \NWC"16;
"S \NAC"
BN"13"36;
%"TAP"
"1","(-400,3400)","0","standard","I301";
;
CDS_LIB"standard"
BODY_TYPE"PLUMBING"
HDL_TAP"TRUE";
"B \NAC \NWC"16;
"S \NAC"
BN"14"37;
%"TAP"
"1","(-200,3150)","0","standard","I302";
;
CDS_LIB"standard"
BODY_TYPE"PLUMBING"
HDL_TAP"TRUE";
"B \NAC \NWC"15;
"S \NAC"
BN"13"32;
%"TAP"
"1","(-200,3350)","0","standard","I303";
;
CDS_LIB"standard"
BODY_TYPE"PLUMBING"
HDL_TAP"TRUE";
"B \NAC \NWC"15;
"S \NAC"
BN"14"34;
%"TAP"
"1","(-200,3550)","0","standard","I304";
;
CDS_LIB"standard"
BODY_TYPE"PLUMBING"
HDL_TAP"TRUE";
"B \NAC \NWC"15;
"S \NAC"
BN"15"33;
%"TAP"
"1","(-400,3600)","0","standard","I305";
;
CDS_LIB"standard"
BODY_TYPE"PLUMBING"
HDL_TAP"TRUE";
"B \NAC \NWC"16;
"S \NAC"
BN"15"35;
%"TAP"
"1","(-200,975)","0","standard","I310";
;
CDS_LIB"standard"
BODY_TYPE"PLUMBING"
HDL_TAP"TRUE";
"B \NAC \NWC"11;
"S \NAC"
BN"4"31;
%"TAP"
"1","(-400,1225)","0","standard","I311";
;
CDS_LIB"standard"
BODY_TYPE"PLUMBING"
HDL_TAP"TRUE";
"B \NAC \NWC"12;
"S \NAC"
BN"5"55;
%"Q_CAP_DIFFBUS"
"2","(-950,1625)","2","pure_quanta","I312";
;
PART_NUMBER"SP_CH4221MEE01"
VALUE"DIFF BUS_0.22UF"
$LOCATION"C726"
PIN_NAMES_ROTATE"TRUE"
CDS_LMAN_SYM_OUTLINE"-25,50,25,-50"
CDS_LIB"pure_quanta"
VOLTAGE"6.3V"
MATERIAL"X6S"
PACK_TYPE"C0201"
TOLERANCE"20%"
$LOCATION"C726"
CDS_LOCATION"C726"
$SEC"1"
CDS_SEC"1";
"2"
$PN"2"74;
"1"
$PN"1"56;
END.
